# T6G (Grand Teton) — schematic netlist excerpt (pin names and nets, part order shuffled) for the footprints in the layout excerpt that follows; sources: Cadence DE-HDL packaged netlist, KiCad conversion of 04192023_DAF0TMB3IC0_F0TG_MB_C_brd_V02_OCP.brd

C2337  Q_CAP  22UF 4V 20% X6S  pkg C0402  page 73 : A = PVDDCR_CPU0_P1 ; B = GND
R2796  Q_RES  0 5% CHIP  pkg 0402LF  page 240 : A = FM_PDB_BUF_EN_R1 ; B = MB_PDB_SMB9_R_EN

(kicad_pcb
	(version 20260206)
	(generator "pcbnew")
	(generator_version "10.0")
	(general
		(thickness 1.6)
		(legacy_teardrops no)
	)
	(paper "A4")
	(title_block
		(title "04192023_DAF0TMB3IC0_F0TG_MB_C_brd_V02_OCP.brd")
		(comment 1 "Grand Teton / footprints 7369-7370 of 8354")
	)
	(layers
		(0 "F.Cu" signal "TOP")
		(4 "In1.Cu" signal "GND")
		(6 "In2.Cu" signal "IN1")
		(8 "In3.Cu" signal "GND1")
		(10 "In4.Cu" signal "IN2")
		(12 "In5.Cu" signal "GND2")
		(14 "In6.Cu" signal "IN3")
		(16 "In7.Cu" signal "GND3")
		(18 "In8.Cu" signal "VCC")
		(20 "In9.Cu" signal "VCC1")
		(22 "In10.Cu" signal "GND4")
		(24 "In11.Cu" signal "IN4")
		(26 "In12.Cu" signal "GND5")
		(28 "In13.Cu" signal "IN5")
		(30 "In14.Cu" signal "GND6")
		(32 "In15.Cu" signal "IN6")
		(34 "In16.Cu" signal "GND7")
		(2 "B.Cu" signal "BOTTOM")
		(9 "F.Adhes" user "F.Adhesive")
		(11 "B.Adhes" user "B.Adhesive")
		(13 "F.Paste" user "Package Geometry/Pastemask Top")
		(15 "B.Paste" user "Package Geometry/Pastemask Bottom")
		(5 "F.SilkS" user "Ref Des/Silkscreen Top")
		(7 "B.SilkS" user "Ref Des/Silkscreen Bottom")
		(1 "F.Mask" user "Board Geometry/Soldermask Top")
		(3 "B.Mask" user "Board Geometry/Soldermask Bottom")
		(17 "Dwgs.User" user "User.Drawings")
		(19 "Cmts.User" user "User.Comments")
		(21 "Eco1.User" user "User.Eco1")
		(23 "Eco2.User" user "User.Eco2")
		(25 "Edge.Cuts" user "Board Geometry/Outline")
		(27 "Margin" user)
		(31 "F.CrtYd" user "Package Geometry/Place Bound Top")
		(29 "B.CrtYd" user "Package Geometry/Place Bound Bottom")
		(35 "F.Fab" user "Ref Des/Assembly Top")
		(33 "B.Fab" user "Ref Des/Assembly Bottom")
	)
	(footprint ""
		(layer "B.Cu")
		(at 184.681114 -419.861238)
		(property "Reference" "R2796"
			(at 0 0 0)
			(layer "B.SilkS")
			(hide yes)
			(effects
				(font
					(size 1.27 1.27)
				)
				(justify mirror)
			)
		)
		(property "Value" ""
			(at 0 0 0)
			(layer "B.Fab")
			(effects
				(font
					(size 1.27 1.27)
				)
				(justify mirror)
			)
		)
		(duplicate_pad_numbers_are_jumpers no)
		(fp_line
			(start -0.7874 -0.4064)
			(end -0.7874 0.4064)
			(stroke
				(width 0.1524)
				(type default)
			)
			(layer "B.SilkS")
		)
		(fp_line
			(start -0.7874 0.4064)
			(end 0.7874 0.4064)
			(stroke
				(width 0.1524)
				(type default)
			)
			(layer "B.SilkS")
		)
		(fp_line
			(start 0.7874 -0.4064)
			(end -0.7874 -0.4064)
			(stroke
				(width 0.1524)
				(type default)
			)
			(layer "B.SilkS")
		)
		(fp_line
			(start 0.7874 0.4064)
			(end 0.7874 -0.4064)
			(stroke
				(width 0.1524)
				(type default)
			)
			(layer "B.SilkS")
		)
		(fp_line
			(start -0.67945 -0.3048)
			(end -0.67945 0.3048)
			(stroke
				(width 0.1)
				(type default)
			)
			(layer "B.Fab")
		)
		(fp_line
			(start -0.67945 0.3048)
			(end -0.120396 0.3048)
			(stroke
				(width 0.1)
				(type default)
			)
			(layer "B.Fab")
		)
		(fp_line
			(start -0.12065 -0.3048)
			(end -0.67945 -0.3048)
			(stroke
				(width 0.1)
				(type default)
			)
			(layer "B.Fab")
		)
		(fp_line
			(start -0.12065 -0.2794)
			(end -0.12065 -0.3048)
			(stroke
				(width 0.1)
				(type default)
			)
			(layer "B.Fab")
		)
		(fp_line
			(start -0.120396 0.2794)
			(end 0.12065 0.2794)
			(stroke
				(width 0.1)
				(type default)
			)
			(layer "B.Fab")
		)
		(fp_line
			(start -0.120396 0.3048)
			(end -0.120396 0.2794)
			(stroke
				(width 0.1)
				(type default)
			)
			(layer "B.Fab")
		)
		(fp_line
			(start 0.12065 -0.305054)
			(end 0.12065 -0.2794)
			(stroke
				(width 0.1)
				(type default)
			)
			(layer "B.Fab")
		)
		(fp_line
			(start 0.12065 -0.2794)
			(end -0.12065 -0.2794)
			(stroke
				(width 0.1)
				(type default)
			)
			(layer "B.Fab")
		)
		(fp_line
			(start 0.12065 0.2794)
			(end 0.12065 0.3048)
			(stroke
				(width 0.1)
				(type default)
			)
			(layer "B.Fab")
		)
		(fp_line
			(start 0.12065 0.3048)
			(end 0.67945 0.3048)
			(stroke
				(width 0.1)
				(type default)
			)
			(layer "B.Fab")
		)
		(fp_line
			(start 0.67945 -0.305054)
			(end 0.12065 -0.305054)
			(stroke
				(width 0.1)
				(type default)
			)
			(layer "B.Fab")
		)
		(fp_line
			(start 0.67945 0.3048)
			(end 0.67945 -0.305054)
			(stroke
				(width 0.1)
				(type default)
			)
			(layer "B.Fab")
		)
		(pad "1" smd circle
			(at 0.40005 0 180)
			(size 0 0)
			(layers "B.Cu" "B.Mask" "B.Paste")
			(net "FM_PDB_BUF_EN_R1")
		)
		(pad "2" smd circle
			(at -0.40005 0 180)
			(size 0 0)
			(layers "B.Cu" "B.Mask" "B.Paste")
			(net "MB_PDB_SMB9_R_EN")
		)
	)
	(footprint ""
		(layer "B.Cu")
		(at 118.277386 -248.479564 180)
		(property "Reference" "C2337"
			(at 0 0 0)
			(layer "B.SilkS")
			(hide yes)
			(effects
				(font
					(size 1.27 1.27)
				)
				(justify mirror)
			)
		)
		(property "Value" ""
			(at 0 0 0)
			(layer "B.Fab")
			(effects
				(font
					(size 1.27 1.27)
				)
				(justify mirror)
			)
		)
		(duplicate_pad_numbers_are_jumpers no)
		(fp_line
			(start 0.7874 0.4064)
			(end 0.7874 -0.4064)
			(stroke
				(width 0.1524)
				(type default)
			)
			(layer "B.SilkS")
		)
		(fp_line
			(start 0.7874 -0.4064)
			(end -0.7874 -0.4064)
			(stroke
				(width 0.1524)
				(type default)
			)
			(layer "B.SilkS")
		)
		(fp_line
			(start -0.7874 0.4064)
			(end 0.7874 0.4064)
			(stroke
				(width 0.1524)
				(type default)
			)
			(layer "B.SilkS")
		)
		(fp_line
			(start -0.7874 -0.4064)
			(end -0.7874 0.4064)
			(stroke
				(width 0.1524)
				(type default)
			)
			(layer "B.SilkS")
		)
		(fp_line
			(start 0.67945 0.3048)
			(end 0.67945 -0.305054)
			(stroke
				(width 0.1)
				(type default)
			)
			(layer "B.Fab")
		)
		(fp_line
			(start 0.67945 -0.305054)
			(end 0.12065 -0.305054)
			(stroke
				(width 0.1)
				(type default)
			)
			(layer "B.Fab")
		)
		(fp_line
			(start 0.12065 0.3048)
			(end 0.67945 0.3048)
			(stroke
				(width 0.1)
				(type default)
			)
			(layer "B.Fab")
		)
		(fp_line
			(start 0.12065 0.2794)
			(end 0.12065 0.3048)
			(stroke
				(width 0.1)
				(type default)
			)
			(layer "B.Fab")
		)
		(fp_line
			(start 0.12065 -0.2794)
			(end -0.12065 -0.2794)
			(stroke
				(width 0.1)
				(type default)
			)
			(layer "B.Fab")
		)
		(fp_line
			(start 0.12065 -0.305054)
			(end 0.12065 -0.2794)
			(stroke
				(width 0.1)
				(type default)
			)
			(layer "B.Fab")
		)
		(fp_line
			(start -0.120396 0.3048)
			(end -0.120396 0.2794)
			(stroke
				(width 0.1)
				(type default)
			)
			(layer "B.Fab")
		)
		(fp_line
			(start -0.120396 0.2794)
			(end 0.12065 0.2794)
			(stroke
				(width 0.1)
				(type default)
			)
			(layer "B.Fab")
		)
		(fp_line
			(start -0.12065 -0.2794)
			(end -0.12065 -0.3048)
			(stroke
				(width 0.1)
				(type default)
			)
			(layer "B.Fab")
		)
		(fp_line
			(start -0.12065 -0.3048)
			(end -0.67945 -0.3048)
			(stroke
				(width 0.1)
				(type default)
			)
			(layer "B.Fab")
		)
		(fp_line
			(start -0.67945 0.3048)
			(end -0.120396 0.3048)
			(stroke
				(width 0.1)
				(type default)
			)
			(layer "B.Fab")
		)
		(fp_line
			(start -0.67945 -0.3048)
			(end -0.67945 0.3048)
			(stroke
				(width 0.1)
				(type default)
			)
			(layer "B.Fab")
		)
		(pad "1" smd circle
			(at 0.40005 0)
			(size 0 0)
			(layers "B.Cu" "B.Mask" "B.Paste")
			(net "PVDDCR_CPU0_P1")
		)
		(pad "2" smd circle
			(at -0.40005 0)
			(size 0 0)
			(layers "B.Cu" "B.Mask" "B.Paste")
			(net "GND")
		)
	)
)
